# S9S_MB_2U (Grand Teton) — schematic netlist excerpt (pin names and nets, part order shuffled) for the footprints in the layout excerpt that follows; sources: Cadence DE-HDL packaged netlist, KiCad conversion of 03242023_DA0F0TMBIJ0_F0T_Motherboard_J_brd_V01_OCP.brd

C958  Q_CAP_DIFFBUS  DIFF BUS_0.22UF 6.3V 20% X6S  pkg C0201  page 173 : \1\ = P5E_CPU0_PE2_TX_C_DN<3> ; \2\ = P5E_CPU0_PE2_TX_DN<3>
R3773  Q_RES  4.7K 5% EMPTY  pkg 0402LF  page 191 : A = P3V3_AUX ; B = RST_SMB_E1S_0_N
C1293  Q_CAP  1UF 25V 10% X6S  pkg C0402  page 134 : A = FM_BMC_EN_DET ; B = GND

(kicad_pcb
	(version 20260206)
	(generator "pcbnew")
	(generator_version "10.0")
	(general
		(thickness 1.6)
		(legacy_teardrops no)
	)
	(paper "A4")
	(title_block
		(title "03242023_DA0F0TMBIJ0_F0T_Motherboard_J_brd_V01_OCP.brd")
		(comment 1 "Grand Teton / footprints 696-698 of 6105")
	)
	(layers
		(0 "F.Cu" signal "TOP")
		(4 "In1.Cu" signal "GND")
		(6 "In2.Cu" signal "IN1")
		(8 "In3.Cu" signal "GND1")
		(10 "In4.Cu" signal "IN2")
		(12 "In5.Cu" signal "GND2")
		(14 "In6.Cu" signal "IN3")
		(16 "In7.Cu" signal "GND3")
		(18 "In8.Cu" signal "VCC")
		(20 "In9.Cu" signal "VCC1")
		(22 "In10.Cu" signal "GND4")
		(24 "In11.Cu" signal "IN4")
		(26 "In12.Cu" signal "GND5")
		(28 "In13.Cu" signal "IN5")
		(30 "In14.Cu" signal "GND6")
		(32 "In15.Cu" signal "IN6")
		(34 "In16.Cu" signal "GND7")
		(2 "B.Cu" signal "BOTTOM")
		(9 "F.Adhes" user "F.Adhesive")
		(11 "B.Adhes" user "B.Adhesive")
		(13 "F.Paste" user "Package Geometry/Pastemask Top")
		(15 "B.Paste" user "Package Geometry/Pastemask Bottom")
		(5 "F.SilkS" user "Ref Des/Silkscreen Top")
		(7 "B.SilkS" user "Ref Des/Silkscreen Bottom")
		(1 "F.Mask" user "Board Geometry/Soldermask Top")
		(3 "B.Mask" user "Board Geometry/Soldermask Bottom")
		(17 "Dwgs.User" user "User.Drawings")
		(19 "Cmts.User" user "User.Comments")
		(21 "Eco1.User" user "User.Eco1")
		(23 "Eco2.User" user "User.Eco2")
		(25 "Edge.Cuts" user "Board Geometry/Outline")
		(27 "Margin" user)
		(31 "F.CrtYd" user "Package Geometry/Place Bound Top")
		(29 "B.CrtYd" user "Package Geometry/Place Bound Bottom")
		(35 "F.Fab" user "Ref Des/Assembly Top")
		(33 "B.Fab" user "Ref Des/Assembly Bottom")
	)
	(footprint ""
		(layer "F.Cu")
		(at 162.848036 -66.091308 180)
		(property "Reference" "R3773"
			(at 0 0 180)
			(layer "F.SilkS")
			(hide yes)
			(effects
				(font
					(size 1.27 1.27)
				)
			)
		)
		(property "Value" ""
			(at 0 0 180)
			(layer "F.Fab")
			(effects
				(font
					(size 1.27 1.27)
				)
			)
		)
		(duplicate_pad_numbers_are_jumpers no)
		(fp_line
			(start 0.7874 0.4064)
			(end -0.7874 0.4064)
			(stroke
				(width 0.1524)
				(type default)
			)
			(layer "F.SilkS")
		)
		(fp_line
			(start 0.7874 -0.4064)
			(end 0.7874 0.4064)
			(stroke
				(width 0.1524)
				(type default)
			)
			(layer "F.SilkS")
		)
		(fp_line
			(start -0.7874 0.4064)
			(end -0.7874 -0.4064)
			(stroke
				(width 0.1524)
				(type default)
			)
			(layer "F.SilkS")
		)
		(fp_line
			(start -0.7874 -0.4064)
			(end 0.7874 -0.4064)
			(stroke
				(width 0.1524)
				(type default)
			)
			(layer "F.SilkS")
		)
		(fp_line
			(start 0.67945 0.3048)
			(end 0.120396 0.3048)
			(stroke
				(width 0.1)
				(type default)
			)
			(layer "F.Fab")
		)
		(fp_line
			(start 0.67945 -0.3048)
			(end 0.67945 0.3048)
			(stroke
				(width 0.1)
				(type default)
			)
			(layer "F.Fab")
		)
		(fp_line
			(start 0.12065 -0.2794)
			(end 0.12065 -0.3048)
			(stroke
				(width 0.1)
				(type default)
			)
			(layer "F.Fab")
		)
		(fp_line
			(start 0.12065 -0.3048)
			(end 0.67945 -0.3048)
			(stroke
				(width 0.1)
				(type default)
			)
			(layer "F.Fab")
		)
		(fp_line
			(start 0.120396 0.3048)
			(end 0.120396 0.2794)
			(stroke
				(width 0.1)
				(type default)
			)
			(layer "F.Fab")
		)
		(fp_line
			(start 0.120396 0.2794)
			(end -0.12065 0.2794)
			(stroke
				(width 0.1)
				(type default)
			)
			(layer "F.Fab")
		)
		(fp_line
			(start -0.12065 0.3048)
			(end -0.67945 0.3048)
			(stroke
				(width 0.1)
				(type default)
			)
			(layer "F.Fab")
		)
		(fp_line
			(start -0.12065 0.2794)
			(end -0.12065 0.3048)
			(stroke
				(width 0.1)
				(type default)
			)
			(layer "F.Fab")
		)
		(fp_line
			(start -0.12065 -0.2794)
			(end 0.12065 -0.2794)
			(stroke
				(width 0.1)
				(type default)
			)
			(layer "F.Fab")
		)
		(fp_line
			(start -0.12065 -0.305054)
			(end -0.12065 -0.2794)
			(stroke
				(width 0.1)
				(type default)
			)
			(layer "F.Fab")
		)
		(fp_line
			(start -0.67945 0.3048)
			(end -0.67945 -0.305054)
			(stroke
				(width 0.1)
				(type default)
			)
			(layer "F.Fab")
		)
		(fp_line
			(start -0.67945 -0.305054)
			(end -0.12065 -0.305054)
			(stroke
				(width 0.1)
				(type default)
			)
			(layer "F.Fab")
		)
		(pad "1" smd circle
			(at -0.40005 0 180)
			(size 0 0)
			(layers "F.Cu" "F.Mask" "F.Paste")
			(net "P3V3_AUX")
		)
		(pad "2" smd circle
			(at 0.40005 0 180)
			(size 0 0)
			(layers "F.Cu" "F.Mask" "F.Paste")
			(net "RST_SMB_E1S_0_N")
		)
	)
	(footprint ""
		(layer "F.Cu")
		(at 96.57588 -55.209948 180)
		(property "Reference" "C1293"
			(at 0 0 180)
			(layer "F.SilkS")
			(hide yes)
			(effects
				(font
					(size 1.27 1.27)
				)
			)
		)
		(property "Value" ""
			(at 0 0 180)
			(layer "F.Fab")
			(effects
				(font
					(size 1.27 1.27)
				)
			)
		)
		(duplicate_pad_numbers_are_jumpers no)
		(fp_line
			(start 0.7874 0.4064)
			(end -0.7874 0.4064)
			(stroke
				(width 0.1524)
				(type default)
			)
			(layer "F.SilkS")
		)
		(fp_line
			(start 0.7874 -0.4064)
			(end 0.7874 0.4064)
			(stroke
				(width 0.1524)
				(type default)
			)
			(layer "F.SilkS")
		)
		(fp_line
			(start -0.7874 0.4064)
			(end -0.7874 -0.4064)
			(stroke
				(width 0.1524)
				(type default)
			)
			(layer "F.SilkS")
		)
		(fp_line
			(start -0.7874 -0.4064)
			(end 0.7874 -0.4064)
			(stroke
				(width 0.1524)
				(type default)
			)
			(layer "F.SilkS")
		)
		(fp_line
			(start 0.67945 0.3048)
			(end 0.120396 0.3048)
			(stroke
				(width 0.1)
				(type default)
			)
			(layer "F.Fab")
		)
		(fp_line
			(start 0.67945 -0.3048)
			(end 0.67945 0.3048)
			(stroke
				(width 0.1)
				(type default)
			)
			(layer "F.Fab")
		)
		(fp_line
			(start 0.12065 -0.2794)
			(end 0.12065 -0.3048)
			(stroke
				(width 0.1)
				(type default)
			)
			(layer "F.Fab")
		)
		(fp_line
			(start 0.12065 -0.3048)
			(end 0.67945 -0.3048)
			(stroke
				(width 0.1)
				(type default)
			)
			(layer "F.Fab")
		)
		(fp_line
			(start 0.120396 0.3048)
			(end 0.120396 0.2794)
			(stroke
				(width 0.1)
				(type default)
			)
			(layer "F.Fab")
		)
		(fp_line
			(start 0.120396 0.2794)
			(end -0.12065 0.2794)
			(stroke
				(width 0.1)
				(type default)
			)
			(layer "F.Fab")
		)
		(fp_line
			(start -0.12065 0.3048)
			(end -0.67945 0.3048)
			(stroke
				(width 0.1)
				(type default)
			)
			(layer "F.Fab")
		)
		(fp_line
			(start -0.12065 0.2794)
			(end -0.12065 0.3048)
			(stroke
				(width 0.1)
				(type default)
			)
			(layer "F.Fab")
		)
		(fp_line
			(start -0.12065 -0.2794)
			(end 0.12065 -0.2794)
			(stroke
				(width 0.1)
				(type default)
			)
			(layer "F.Fab")
		)
		(fp_line
			(start -0.12065 -0.305054)
			(end -0.12065 -0.2794)
			(stroke
				(width 0.1)
				(type default)
			)
			(layer "F.Fab")
		)
		(fp_line
			(start -0.67945 0.3048)
			(end -0.67945 -0.305054)
			(stroke
				(width 0.1)
				(type default)
			)
			(layer "F.Fab")
		)
		(fp_line
			(start -0.67945 -0.305054)
			(end -0.12065 -0.305054)
			(stroke
				(width 0.1)
				(type default)
			)
			(layer "F.Fab")
		)
		(pad "1" smd circle
			(at -0.40005 0 180)
			(size 0 0)
			(layers "F.Cu" "F.Mask" "F.Paste")
			(net "FM_BMC_EN_DET")
		)
		(pad "2" smd circle
			(at 0.40005 0 180)
			(size 0 0)
			(layers "F.Cu" "F.Mask" "F.Paste")
			(net "GND")
		)
	)
	(footprint ""
		(layer "F.Cu")
		(at 409.07081 -402.371052 -90)
		(property "Reference" "C958"
			(at 0 0 270)
			(layer "F.SilkS")
			(hide yes)
			(effects
				(font
					(size 1.27 1.27)
				)
			)
		)
		(property "Value" ""
			(at 0 0 270)
			(layer "F.Fab")
			(effects
				(font
					(size 1.27 1.27)
				)
			)
		)
		(duplicate_pad_numbers_are_jumpers no)
		(fp_line
			(start -0.299974 0.150114)
			(end -0.299974 -0.150114)
			(stroke
				(width 0.1)
				(type default)
			)
			(layer "F.Fab")
		)
		(fp_line
			(start 0.299974 0.150114)
			(end -0.299974 0.150114)
			(stroke
				(width 0.1)
				(type default)
			)
			(layer "F.Fab")
		)
		(fp_line
			(start -0.299974 -0.150114)
			(end 0.299974 -0.150114)
			(stroke
				(width 0.1)
				(type default)
			)
			(layer "F.Fab")
		)
		(fp_line
			(start 0.299974 -0.150114)
			(end 0.299974 0.150114)
			(stroke
				(width 0.1)
				(type default)
			)
			(layer "F.Fab")
		)
		(pad "1" smd rect
			(at -0.2667 0 270)
			(size 0.3048 0.381)
			(layers "F.Cu" "F.Mask" "F.Paste")
			(net "P5E_CPU0_PE2_TX_C_DN<3>")
		)
		(pad "2" smd rect
			(at 0.2667 0 270)
			(size 0.3048 0.381)
			(layers "F.Cu" "F.Mask" "F.Paste")
			(net "P5E_CPU0_PE2_TX_DN<3>")
		)
	)
)
